# TIMECARD (Time Appliance Project (Time Card)) — schematic netlist excerpt (pin names and nets, part order shuffled) for the footprints in the layout excerpt that follows; sources: Cadence DE-HDL packaged netlist, KiCad conversion of R4006-B0001-02_R01.brd

C76  CAPACITOR  0.1UF 25V 10%  pkg SMC_0402R_H022  page 28 : \1\ = XP12R0V ; \2\ = SG

(kicad_pcb
	(version 20260206)
	(generator "pcbnew")
	(generator_version "10.0")
	(general
		(thickness 1.6)
		(legacy_teardrops no)
	)
	(paper "A4")
	(title_block
		(title "timecard-production-celestica-r4006 — R4006-B0001-02_R01.brd")
		(comment 1 "Time Appliance Project (Time Card) / footprints 545-545 of 1113")
	)
	(layers
		(0 "F.Cu" signal "TOP")
		(4 "In1.Cu" signal "L02_GND1")
		(6 "In2.Cu" signal "L03_SIG1")
		(8 "In3.Cu" signal "L04_GND2")
		(10 "In4.Cu" signal "L05_VCC1")
		(12 "In5.Cu" signal "L06_VCC2")
		(14 "In6.Cu" signal "L07_GND3")
		(16 "In7.Cu" signal "L08_SIG2")
		(18 "In8.Cu" signal "L09_GND4")
		(2 "B.Cu" signal "BOTTOM")
		(9 "F.Adhes" user "F.Adhesive")
		(11 "B.Adhes" user "B.Adhesive")
		(13 "F.Paste" user "Package Geometry/Pastemask Top")
		(15 "B.Paste" user "Package Geometry/Pastemask Bottom")
		(5 "F.SilkS" user "Ref Des/Silkscreen Top")
		(7 "B.SilkS" user "Ref Des/Silkscreen Bottom")
		(1 "F.Mask" user "Board Geometry/Soldermask Top")
		(3 "B.Mask" user "Board Geometry/Soldermask Bottom")
		(17 "Dwgs.User" user "User.Drawings")
		(19 "Cmts.User" user "User.Comments")
		(21 "Eco1.User" user "User.Eco1")
		(23 "Eco2.User" user "User.Eco2")
		(25 "Edge.Cuts" user "Board Geometry/Outline")
		(27 "Margin" user)
		(31 "F.CrtYd" user "Package Geometry/Place Bound Top")
		(29 "B.CrtYd" user "Package Geometry/Place Bound Bottom")
		(35 "F.Fab" user "Ref Des/Assembly Top")
		(33 "B.Fab" user "Ref Des/Assembly Bottom")
	)
	(footprint ""
		(layer "F.Cu")
		(at 90.7542 -106.6038)
		(property "Reference" "C76"
			(at 0.0508 -1.81483 0)
			(unlocked yes)
			(layer "F.SilkS")
			(effects
				(font
					(size 0.7874 0.5842)
					(thickness 0.1524)
				)
			)
		)
		(property "Value" "VAL*"
			(at 0.0762 2.067306 0)
			(unlocked yes)
			(layer "F.Fab")
			(hide yes)
			(effects
				(font
					(size 0.7874 0.5842)
					(thickness 0.1524)
				)
			)
		)
		(property "Tolerance" "TOL*"
			(at 0.0762 3.032506 0)
			(unlocked yes)
			(layer "Cmts.User")
			(hide yes)
			(effects
				(font
					(size 0.7874 0.5842)
					(thickness 0.1524)
				)
			)
		)
		(property "User Part Number" "PARTNUM*"
			(at 0.1016 4.023106 0)
			(unlocked yes)
			(layer "Cmts.User")
			(hide yes)
			(effects
				(font
					(size 0.7874 0.5842)
					(thickness 0.1524)
				)
			)
		)
		(property "Device Type" "CAPACITOR-G105-0B104-EK,0.1UF,A"
			(at 0.0508 1.127506 0)
			(unlocked yes)
			(layer "F.Fab")
			(hide yes)
			(effects
				(font
					(size 0.7874 0.5842)
					(thickness 0.1524)
				)
			)
		)
		(duplicate_pad_numbers_are_jumpers no)
		(fp_line
			(start -1.143 -0.5588)
			(end -1.143 0.5588)
			(stroke
				(width 0.1)
				(type default)
			)
			(layer "F.SilkS")
		)
		(fp_line
			(start -1.143 0.5588)
			(end 1.143 0.5588)
			(stroke
				(width 0.1)
				(type default)
			)
			(layer "F.SilkS")
		)
		(fp_line
			(start 1.143 -0.5588)
			(end -1.143 -0.5588)
			(stroke
				(width 0.1)
				(type default)
			)
			(layer "F.SilkS")
		)
		(fp_line
			(start 1.143 0.5588)
			(end 1.143 -0.5588)
			(stroke
				(width 0.1)
				(type default)
			)
			(layer "F.SilkS")
		)
		(fp_rect
			(start -1.143 0.5588)
			(end 1.143 -0.5588)
			(stroke
				(width 0)
				(type default)
			)
			(fill no)
			(layer "F.CrtYd")
		)
		(fp_line
			(start -0.508 -0.3048)
			(end -0.508 0.3048)
			(stroke
				(width 0.1)
				(type default)
			)
			(layer "F.Fab")
		)
		(fp_line
			(start -0.508 0.3048)
			(end 0.508 0.3048)
			(stroke
				(width 0.1)
				(type default)
			)
			(layer "F.Fab")
		)
		(fp_line
			(start 0.508 -0.3048)
			(end -0.508 -0.3048)
			(stroke
				(width 0.1)
				(type default)
			)
			(layer "F.Fab")
		)
		(fp_line
			(start 0.508 0.3048)
			(end 0.508 -0.3048)
			(stroke
				(width 0.1)
				(type default)
			)
			(layer "F.Fab")
		)
		(pad "1" smd rect
			(at -0.5334 0)
			(size 0.7112 0.6096)
			(layers "F.Cu" "F.Mask" "F.Paste")
			(net "XP12R0V")
		)
		(pad "2" smd rect
			(at 0.5334 0)
			(size 0.7112 0.6096)
			(layers "F.Cu" "F.Mask" "F.Paste")
			(net "SG")
		)
		(zone
			(layer "F.Cu")
			(hatch none 0.5)
			(connect_pads
				(clearance 0)
			)
			(min_thickness 0.25)
			(keepout
				(tracks allowed)
				(vias not_allowed)
				(pads allowed)
				(copperpour not_allowed)
				(footprints allowed)
			)
			(placement
				(enabled no)
				(sheetname "")
			)
			(fill
				(thermal_gap 0.5)
				(thermal_bridge_width 0.5)
				(island_removal_mode 0)
			)
			(polygon
				(pts
					(xy 90.678 -106.299) (xy 90.8304 -106.299) (xy 90.8304 -106.9086) (xy 90.678 -106.9086)
				)
			)
		)
	)
)
